(kicad_pcb
	(version 20221018)
	(generator pcbnew)
	(general
    (thickness 1.62)
  )
	(paper "A4")
	(title_block
    (title "ECP5 - Datacenter Secure Control Module (DC-SCM)")
    (date "2024-07-01")
    (rev "1.2.1")
		(comment 9 "footprints 221-228 of 506")
	)
	(layers
    (0 "F.Cu" signal)
    (1 "In1.Cu" power)
    (2 "In2.Cu" signal)
    (3 "In3.Cu" power)
    (4 "In4.Cu" power)
    (5 "In5.Cu" signal)
    (6 "In6.Cu" power)
    (31 "B.Cu" signal)
    (32 "B.Adhes" user "B.Adhesive")
    (33 "F.Adhes" user "F.Adhesive")
    (34 "B.Paste" user)
    (35 "F.Paste" user)
    (36 "B.SilkS" user "B.Silkscreen")
    (37 "F.SilkS" user "F.Silkscreen")
    (38 "B.Mask" user)
    (39 "F.Mask" user)
    (40 "Dwgs.User" user "User.Drawings")
    (41 "Cmts.User" user "User.Comments")
    (42 "Eco1.User" user "User.Eco1")
    (43 "Eco2.User" user "User.Eco2")
    (44 "Edge.Cuts" user)
    (45 "Margin" user)
    (46 "B.CrtYd" user "B.Courtyard")
    (47 "F.CrtYd" user "F.Courtyard")
    (48 "B.Fab" user)
    (49 "F.Fab" user)
  )
	(footprint "antmicro-footprints:SOT-23-3" (layer "B.Cu")
    (at 75.15 93.3 180)
    (property "Author" "Antmicro")
    (property "License" "Apache-2.0")
    (property "MPN" "2N7002")
    (property "Manufacturer" "ON Semiconductor")
    (property "Sheetfile" "power-supply.kicad_sch")
    (property "Sheetname" "Power supply")
    (property "ki_description" "Power MOSFET, N Channel, 60 V, 115 mA, 1.2 ohm, SOT-23, Surface Mount")
    (property "ki_keywords" "SMT, TRANSISTOR, SEMICONDUCTOR, NMOS")
    (attr smd)
    (fp_text reference "Q15" (at 0.025 -2.6 180) (layer "B.SilkS")
        (effects (font (size 0.7 0.7) (thickness 0.127)) (justify mirror))
    )
    (fp_text value "2N7002" (at 0.025 -3.25 180) (layer "B.Fab")
        (effects (font (size 1 1) (thickness 0.15)) (justify mirror))
    )
    (fp_text user "License: Apache-2.0" (at -1.8 -6.8) (layer "B.Fab") hide
        (effects (font (size 0.7 0.7) (thickness 0.15)) (justify left bottom mirror))
    )
    (fp_text user "Author: Antmicro" (at -1.837 -5.3) (layer "B.Fab") hide
        (effects (font (size 0.7 0.7) (thickness 0.15)) (justify left bottom mirror))
    )
    (fp_text user "${REFERENCE}" (at -0.125 -0.15 180) (layer "B.Fab")
        (effects (font (size 0.25 0.25) (thickness 0.05)) (justify mirror))
    )
    (fp_line (start -1.45 1.35) (end -0.85 1.35)
      (stroke (width 0.15) (type solid)) (layer "B.SilkS"))
    (fp_line (start -0.85 1.35) (end -0.7 1.5)
      (stroke (width 0.15) (type solid)) (layer "B.SilkS"))
    (fp_line (start -0.7 -1.5) (end -0.7 -1.35)
      (stroke (width 0.15) (type solid)) (layer "B.SilkS"))
    (fp_line (start 0.7 -1.5) (end -0.7 -1.5)
      (stroke (width 0.15) (type solid)) (layer "B.SilkS"))
    (fp_line (start 0.7 -0.4) (end 0.7 -1.5)
      (stroke (width 0.15) (type solid)) (layer "B.SilkS"))
    (fp_line (start 0.7 0.4) (end 0.7 1.5)
      (stroke (width 0.15) (type solid)) (layer "B.SilkS"))
    (fp_line (start 0.7 1.5) (end -0.7 1.5)
      (stroke (width 0.15) (type solid)) (layer "B.SilkS"))
    (fp_line (start -1.75 -1.4) (end -1.75 -0.5)
      (stroke (width 0.05) (type solid)) (layer "B.CrtYd"))
    (fp_line (start -1.75 -0.5) (end -0.85 -0.5)
      (stroke (width 0.05) (type solid)) (layer "B.CrtYd"))
    (fp_line (start -1.75 0.5) (end -1.75 1.4)
      (stroke (width 0.05) (type solid)) (layer "B.CrtYd"))
    (fp_line (start -0.9 1.4) (end -1.75 1.4)
      (stroke (width 0.05) (type solid)) (layer "B.CrtYd"))
    (fp_line (start -0.9 1.6) (end -0.9 1.4)
      (stroke (width 0.05) (type solid)) (layer "B.CrtYd"))
    (fp_line (start -0.9 1.6) (end 0.825 1.6)
      (stroke (width 0.05) (type solid)) (layer "B.CrtYd"))
    (fp_line (start -0.85 -1.65) (end -0.85 -1.4)
      (stroke (width 0.05) (type solid)) (layer "B.CrtYd"))
    (fp_line (start -0.85 -1.4) (end -1.75 -1.4)
      (stroke (width 0.05) (type solid)) (layer "B.CrtYd"))
    (fp_line (start -0.85 -0.5) (end -0.85 0.5)
      (stroke (width 0.05) (type solid)) (layer "B.CrtYd"))
    (fp_line (start -0.85 0.5) (end -1.75 0.5)
      (stroke (width 0.05) (type solid)) (layer "B.CrtYd"))
    (fp_line (start 0.825 0.45) (end 1.75 0.45)
      (stroke (width 0.05) (type solid)) (layer "B.CrtYd"))
    (fp_line (start 0.825 1.6) (end 0.825 0.45)
      (stroke (width 0.05) (type solid)) (layer "B.CrtYd"))
    (fp_line (start 0.85 -1.65) (end -0.85 -1.65)
      (stroke (width 0.05) (type solid)) (layer "B.CrtYd"))
    (fp_line (start 0.85 -0.45) (end 0.85 -1.65)
      (stroke (width 0.05) (type solid)) (layer "B.CrtYd"))
    (fp_line (start 1.75 -0.45) (end 0.85 -0.45)
      (stroke (width 0.05) (type solid)) (layer "B.CrtYd"))
    (fp_line (start 1.75 0.45) (end 1.75 -0.45)
      (stroke (width 0.05) (type solid)) (layer "B.CrtYd"))
    (fp_line (start -0.712 -1.519) (end 0.688 -1.519)
      (stroke (width 0.15) (type solid)) (layer "B.Fab"))
    (fp_line (start -0.712 1.325) (end -0.712 -1.523)
      (stroke (width 0.15) (type solid)) (layer "B.Fab"))
    (fp_line (start -0.437 1.526) (end -0.712 1.325)
      (stroke (width 0.15) (type solid)) (layer "B.Fab"))
    (fp_line (start -0.437 1.526) (end 0.688 1.526)
      (stroke (width 0.15) (type solid)) (layer "B.Fab"))
    (fp_line (start 0.688 -1.519) (end 0.688 1.52)
      (stroke (width 0.15) (type solid)) (layer "B.Fab"))
    (pad "1" smd roundrect (at -1.1 0.951 180) (size 1 0.6) (layers "B.Cu" "B.Paste" "B.Mask") (roundrect_rratio 0.15)
      (net 223 "/Power supply/1V8_PG") (pinfunction "G") (pintype "passive"))
    (pad "2" smd roundrect (at -1.1 -0.949 180) (size 1 0.6) (layers "B.Cu" "B.Paste" "B.Mask") (roundrect_rratio 0.15)
      (net 1 "GND") (pinfunction "S") (pintype "passive"))
    (pad "3" smd roundrect (at 1.1 0.0005 180) (size 1 0.6) (layers "B.Cu" "B.Paste" "B.Mask") (roundrect_rratio 0.15)
      (net 399 "Net-(Q15-D)") (pinfunction "D") (pintype "passive"))
  )
	(footprint "antmicro-footprints:R_0402_1005Metric" (layer "B.Cu")
    (at 89.15 87.55 180)
    (descr "Resistor SMD 0402")
    (tags "resistor SMD 0402")
    (property "Author" "Antmicro")
    (property "License" "Apache-2.0")
    (property "MPN" "CR0402-FX-1002GLF")
    (property "Manufacturer" "Bourns")
    (property "Public" "False")
    (property "Sheetfile" "power-supply.kicad_sch")
    (property "Sheetname" "Power supply")
    (property "Tolerance" "1%")
    (property "Val" "10k")
    (property "ki_description" "SMD Chip Resistor, 10 kohm, ± 1%, 62.5 mW, 0402 [1005 Metric], Thick Film, General Purpose")
    (property "ki_keywords" "0402, SMT, RESISTOR, PASSIVE")
    (attr smd)
    (fp_text reference "R104" (at 0 1.17 180) (layer "B.SilkS")
        (effects (font (size 0.7 0.7) (thickness 0.127)) (justify mirror))
    )
    (fp_text value "R_10k_0402" (at 0 -1.17 180) (layer "B.Fab")
        (effects (font (size 1 1) (thickness 0.15)) (justify mirror))
    )
    (fp_text user "${REFERENCE}" (at 0 0 180) (layer "B.Fab")
        (effects (font (size 0.25 0.25) (thickness 0.04)) (justify mirror))
    )
    (fp_text user "Author: Antmicro" (at -0.95 -4.169) (layer "B.Fab") hide
        (effects (font (size 0.7 0.7) (thickness 0.15)) (justify left bottom mirror))
    )
    (fp_text user "License: Apache-2.0" (at -0.95 -5.169) (layer "B.Fab") hide
        (effects (font (size 0.7 0.7) (thickness 0.15)) (justify left bottom mirror))
    )
    (fp_rect (start -0.925 0.47) (end 0.925 -0.47)
      (stroke (width 0.05) (type default)) (fill none) (layer "B.CrtYd"))
    (fp_rect (start -0.5 0.25) (end 0.5 -0.25)
      (stroke (width 0.15) (type solid)) (fill none) (layer "B.Fab"))
    (pad "1" smd roundrect (at -0.48 0 180) (size 0.59 0.64) (layers "B.Cu" "B.Paste" "B.Mask") (roundrect_rratio 0.25)
      (net 11 "VCC5V0") (pintype "passive"))
    (pad "2" smd roundrect (at 0.48 0 180) (size 0.59 0.64) (layers "B.Cu" "B.Paste" "B.Mask") (roundrect_rratio 0.25)
      (net 236 "/Power supply/2V5_PG") (pintype "passive"))
  )
	(footprint "antmicro-footprints:R_0402_1005Metric" (layer "B.Cu")
    (at 117.909056 89.493104 180)
    (descr "Resistor SMD 0402")
    (tags "resistor SMD 0402")
    (property "Author" "Antmicro")
    (property "License" "Apache-2.0")
    (property "MPN" "CR0402-FX-1002GLF")
    (property "Manufacturer" "Bourns")
    (property "Public" "False")
    (property "Sheetfile" "power-supply.kicad_sch")
    (property "Sheetname" "Power supply")
    (property "Tolerance" "1%")
    (property "Val" "10k")
    (property "ki_description" "SMD Chip Resistor, 10 kohm, ± 1%, 62.5 mW, 0402 [1005 Metric], Thick Film, General Purpose")
    (property "ki_keywords" "0402, SMT, RESISTOR, PASSIVE")
    (attr smd)
    (fp_text reference "R105" (at 0 0.95 180) (layer "B.SilkS")
        (effects (font (size 0.7 0.7) (thickness 0.127)) (justify mirror))
    )
    (fp_text value "R_10k_0402" (at 0 -1.17 180) (layer "B.Fab")
        (effects (font (size 1 1) (thickness 0.15)) (justify mirror))
    )
    (fp_text user "Author: Antmicro" (at -0.95 -4.169) (layer "B.Fab") hide
        (effects (font (size 0.7 0.7) (thickness 0.15)) (justify left bottom mirror))
    )
    (fp_text user "License: Apache-2.0" (at -0.95 -5.169) (layer "B.Fab") hide
        (effects (font (size 0.7 0.7) (thickness 0.15)) (justify left bottom mirror))
    )
    (fp_text user "${REFERENCE}" (at 0 0 180) (layer "B.Fab")
        (effects (font (size 0.25 0.25) (thickness 0.04)) (justify mirror))
    )
    (fp_rect (start -0.925 0.47) (end 0.925 -0.47)
      (stroke (width 0.05) (type default)) (fill none) (layer "B.CrtYd"))
    (fp_rect (start -0.5 0.25) (end 0.5 -0.25)
      (stroke (width 0.15) (type solid)) (fill none) (layer "B.Fab"))
    (pad "1" smd roundrect (at -0.48 0 180) (size 0.59 0.64) (layers "B.Cu" "B.Paste" "B.Mask") (roundrect_rratio 0.25)
      (net 11 "VCC5V0") (pintype "passive"))
    (pad "2" smd roundrect (at 0.48 0 180) (size 0.59 0.64) (layers "B.Cu" "B.Paste" "B.Mask") (roundrect_rratio 0.25)
      (net 223 "/Power supply/1V8_PG") (pintype "passive"))
  )
	(footprint "antmicro-footprints:R_0402_1005Metric" (layer "B.Cu")
    (at 64.25 86.7 180)
    (descr "Resistor SMD 0402")
    (tags "resistor SMD 0402")
    (property "Author" "Antmicro")
    (property "License" "Apache-2.0")
    (property "MPN" "CR0402-FX-1001GLF")
    (property "Manufacturer" "Bourns")
    (property "Public" "False")
    (property "Sheetfile" "power-supply.kicad_sch")
    (property "Sheetname" "Power supply")
    (property "Tolerance" "1%")
    (property "Val" "1k")
    (property "ki_description" "SMD Chip Resistor, 1 kohm, ± 1%, 63 mW, 0402 [1005 Metric], Thick Film, General Purpose")
    (property "ki_keywords" "0402, SMT, RESISTOR, PASSIVE")
    (attr smd)
    (fp_text reference "R107" (at 0.13 0.805 180) (layer "B.SilkS")
        (effects (font (size 0.7 0.7) (thickness 0.127)) (justify mirror))
    )
    (fp_text value "R_1k_0402" (at 0 -1.17 180) (layer "B.Fab")
        (effects (font (size 1 1) (thickness 0.15)) (justify mirror))
    )
    (fp_text user "License: Apache-2.0" (at -0.95 -5.169) (layer "B.Fab") hide
        (effects (font (size 0.7 0.7) (thickness 0.15)) (justify left bottom mirror))
    )
    (fp_text user "Author: Antmicro" (at -0.95 -4.169) (layer "B.Fab") hide
        (effects (font (size 0.7 0.7) (thickness 0.15)) (justify left bottom mirror))
    )
    (fp_text user "${REFERENCE}" (at 0 0 180) (layer "B.Fab")
        (effects (font (size 0.25 0.25) (thickness 0.04)) (justify mirror))
    )
    (fp_rect (start -0.925 0.47) (end 0.925 -0.47)
      (stroke (width 0.05) (type default)) (fill none) (layer "B.CrtYd"))
    (fp_rect (start -0.5 0.25) (end 0.5 -0.25)
      (stroke (width 0.15) (type solid)) (fill none) (layer "B.Fab"))
    (pad "1" smd roundrect (at -0.48 0 180) (size 0.59 0.64) (layers "B.Cu" "B.Paste" "B.Mask") (roundrect_rratio 0.25)
      (net 394 "Net-(Q10-D)") (pintype "passive"))
    (pad "2" smd roundrect (at 0.48 0 180) (size 0.59 0.64) (layers "B.Cu" "B.Paste" "B.Mask") (roundrect_rratio 0.25)
      (net 315 "Net-(D7-A)") (pintype "passive"))
  )
	(footprint "antmicro-footprints:R_0402_1005Metric" (layer "B.Cu")
    (at 64.25 85.05 180)
    (descr "Resistor SMD 0402")
    (tags "resistor SMD 0402")
    (property "Author" "Antmicro")
    (property "License" "Apache-2.0")
    (property "MPN" "CR0402-FX-1001GLF")
    (property "Manufacturer" "Bourns")
    (property "Public" "False")
    (property "Sheetfile" "power-supply.kicad_sch")
    (property "Sheetname" "Power supply")
    (property "Tolerance" "1%")
    (property "Val" "1k")
    (property "ki_description" "SMD Chip Resistor, 1 kohm, ± 1%, 63 mW, 0402 [1005 Metric], Thick Film, General Purpose")
    (property "ki_keywords" "0402, SMT, RESISTOR, PASSIVE")
    (attr smd)
    (fp_text reference "R108" (at 0.17 0.765 180) (layer "B.SilkS")
        (effects (font (size 0.7 0.7) (thickness 0.127)) (justify mirror))
    )
    (fp_text value "R_1k_0402" (at 0 -1.17 180) (layer "B.Fab")
        (effects (font (size 1 1) (thickness 0.15)) (justify mirror))
    )
    (fp_text user "Author: Antmicro" (at -0.95 -4.169) (layer "B.Fab") hide
        (effects (font (size 0.7 0.7) (thickness 0.15)) (justify left bottom mirror))
    )
    (fp_text user "${REFERENCE}" (at 0 0 180) (layer "B.Fab")
        (effects (font (size 0.25 0.25) (thickness 0.04)) (justify mirror))
    )
    (fp_text user "License: Apache-2.0" (at -0.95 -5.169) (layer "B.Fab") hide
        (effects (font (size 0.7 0.7) (thickness 0.15)) (justify left bottom mirror))
    )
    (fp_rect (start -0.925 0.47) (end 0.925 -0.47)
      (stroke (width 0.05) (type default)) (fill none) (layer "B.CrtYd"))
    (fp_rect (start -0.5 0.25) (end 0.5 -0.25)
      (stroke (width 0.15) (type solid)) (fill none) (layer "B.Fab"))
    (pad "1" smd roundrect (at -0.48 0 180) (size 0.59 0.64) (layers "B.Cu" "B.Paste" "B.Mask") (roundrect_rratio 0.25)
      (net 395 "Net-(Q11-D)") (pintype "passive"))
    (pad "2" smd roundrect (at 0.48 0 180) (size 0.59 0.64) (layers "B.Cu" "B.Paste" "B.Mask") (roundrect_rratio 0.25)
      (net 316 "Net-(D8-A)") (pintype "passive"))
  )
	(footprint "antmicro-footprints:R_0402_1005Metric" (layer "B.Cu")
    (at 64.25 94.95 180)
    (descr "Resistor SMD 0402")
    (tags "resistor SMD 0402")
    (property "Author" "Antmicro")
    (property "License" "Apache-2.0")
    (property "MPN" "CR0402-FX-1001GLF")
    (property "Manufacturer" "Bourns")
    (property "Public" "False")
    (property "Sheetfile" "power-supply.kicad_sch")
    (property "Sheetname" "Power supply")
    (property "Tolerance" "1%")
    (property "Val" "1k")
    (property "ki_description" "SMD Chip Resistor, 1 kohm, ± 1%, 63 mW, 0402 [1005 Metric], Thick Film, General Purpose")
    (property "ki_keywords" "0402, SMT, RESISTOR, PASSIVE")
    (attr smd)
    (fp_text reference "R109" (at -0.07 -0.895 180) (layer "B.SilkS")
        (effects (font (size 0.7 0.7) (thickness 0.127)) (justify mirror))
    )
    (fp_text value "R_1k_0402" (at 0 -1.17 180) (layer "B.Fab")
        (effects (font (size 1 1) (thickness 0.15)) (justify mirror))
    )
    (fp_text user "License: Apache-2.0" (at -0.95 -5.169) (layer "B.Fab") hide
        (effects (font (size 0.7 0.7) (thickness 0.15)) (justify left bottom mirror))
    )
    (fp_text user "${REFERENCE}" (at 0 0 180) (layer "B.Fab")
        (effects (font (size 0.25 0.25) (thickness 0.04)) (justify mirror))
    )
    (fp_text user "Author: Antmicro" (at -0.95 -4.169) (layer "B.Fab") hide
        (effects (font (size 0.7 0.7) (thickness 0.15)) (justify left bottom mirror))
    )
    (fp_rect (start -0.925 0.47) (end 0.925 -0.47)
      (stroke (width 0.05) (type default)) (fill none) (layer "B.CrtYd"))
    (fp_rect (start -0.5 0.25) (end 0.5 -0.25)
      (stroke (width 0.15) (type solid)) (fill none) (layer "B.Fab"))
    (pad "1" smd roundrect (at -0.48 0 180) (size 0.59 0.64) (layers "B.Cu" "B.Paste" "B.Mask") (roundrect_rratio 0.25)
      (net 396 "Net-(Q12-D)") (pintype "passive"))
    (pad "2" smd roundrect (at 0.48 0 180) (size 0.59 0.64) (layers "B.Cu" "B.Paste" "B.Mask") (roundrect_rratio 0.25)
      (net 343 "Net-(D9-A)") (pintype "passive"))
  )
	(footprint "antmicro-footprints:R_0402_1005Metric" (layer "B.Cu")
    (at 64.25 93.3 180)
    (descr "Resistor SMD 0402")
    (tags "resistor SMD 0402")
    (property "Author" "Antmicro")
    (property "License" "Apache-2.0")
    (property "MPN" "CR0402-FX-1001GLF")
    (property "Manufacturer" "Bourns")
    (property "Public" "False")
    (property "Sheetfile" "power-supply.kicad_sch")
    (property "Sheetname" "Power supply")
    (property "Tolerance" "1%")
    (property "Val" "1k")
    (property "ki_description" "SMD Chip Resistor, 1 kohm, ± 1%, 63 mW, 0402 [1005 Metric], Thick Film, General Purpose")
    (property "ki_keywords" "0402, SMT, RESISTOR, PASSIVE")
    (attr smd)
    (fp_text reference "R110" (at 0.15 0.8 180) (layer "B.SilkS")
        (effects (font (size 0.7 0.7) (thickness 0.127)) (justify mirror))
    )
    (fp_text value "R_1k_0402" (at 0 -1.17 180) (layer "B.Fab")
        (effects (font (size 1 1) (thickness 0.15)) (justify mirror))
    )
    (fp_text user "Author: Antmicro" (at -0.95 -4.169) (layer "B.Fab") hide
        (effects (font (size 0.7 0.7) (thickness 0.15)) (justify left bottom mirror))
    )
    (fp_text user "${REFERENCE}" (at 0 0 180) (layer "B.Fab")
        (effects (font (size 0.25 0.25) (thickness 0.04)) (justify mirror))
    )
    (fp_text user "License: Apache-2.0" (at -0.95 -5.169) (layer "B.Fab") hide
        (effects (font (size 0.7 0.7) (thickness 0.15)) (justify left bottom mirror))
    )
    (fp_rect (start -0.925 0.47) (end 0.925 -0.47)
      (stroke (width 0.05) (type default)) (fill none) (layer "B.CrtYd"))
    (fp_rect (start -0.5 0.25) (end 0.5 -0.25)
      (stroke (width 0.15) (type solid)) (fill none) (layer "B.Fab"))
    (pad "1" smd roundrect (at -0.48 0 180) (size 0.59 0.64) (layers "B.Cu" "B.Paste" "B.Mask") (roundrect_rratio 0.25)
      (net 397 "Net-(Q13-D)") (pintype "passive"))
    (pad "2" smd roundrect (at 0.48 0 180) (size 0.59 0.64) (layers "B.Cu" "B.Paste" "B.Mask") (roundrect_rratio 0.25)
      (net 344 "Net-(D10-A)") (pintype "passive"))
  )
	(footprint "antmicro-footprints:R_0402_1005Metric" (layer "B.Cu")
    (at 64.25 91.65 180)
    (descr "Resistor SMD 0402")
    (tags "resistor SMD 0402")
    (property "Author" "Antmicro")
    (property "License" "Apache-2.0")
    (property "MPN" "CR0402-FX-1001GLF")
    (property "Manufacturer" "Bourns")
    (property "Public" "False")
    (property "Sheetfile" "power-supply.kicad_sch")
    (property "Sheetname" "Power supply")
    (property "Tolerance" "1%")
    (property "Val" "1k")
    (property "ki_description" "SMD Chip Resistor, 1 kohm, ± 1%, 63 mW, 0402 [1005 Metric], Thick Film, General Purpose")
    (property "ki_keywords" "0402, SMT, RESISTOR, PASSIVE")
    (attr smd)
    (fp_text reference "R111" (at 0.15 0.8 180) (layer "B.SilkS")
        (effects (font (size 0.7 0.7) (thickness 0.127)) (justify mirror))
    )
    (fp_text value "R_1k_0402" (at 0 -1.17 180) (layer "B.Fab")
        (effects (font (size 1 1) (thickness 0.15)) (justify mirror))
    )
    (fp_text user "${REFERENCE}" (at 0 0 180) (layer "B.Fab")
        (effects (font (size 0.25 0.25) (thickness 0.04)) (justify mirror))
    )
    (fp_text user "License: Apache-2.0" (at -0.95 -5.169) (layer "B.Fab") hide
        (effects (font (size 0.7 0.7) (thickness 0.15)) (justify left bottom mirror))
    )
    (fp_text user "Author: Antmicro" (at -0.95 -4.169) (layer "B.Fab") hide
        (effects (font (size 0.7 0.7) (thickness 0.15)) (justify left bottom mirror))
    )
    (fp_rect (start -0.925 0.47) (end 0.925 -0.47)
      (stroke (width 0.05) (type default)) (fill none) (layer "B.CrtYd"))
    (fp_rect (start -0.5 0.25) (end 0.5 -0.25)
      (stroke (width 0.15) (type solid)) (fill none) (layer "B.Fab"))
    (pad "1" smd roundrect (at -0.48 0 180) (size 0.59 0.64) (layers "B.Cu" "B.Paste" "B.Mask") (roundrect_rratio 0.25)
      (net 398 "Net-(Q14-D)") (pintype "passive"))
    (pad "2" smd roundrect (at 0.48 0 180) (size 0.59 0.64) (layers "B.Cu" "B.Paste" "B.Mask") (roundrect_rratio 0.25)
      (net 345 "Net-(D11-A)") (pintype "passive"))
  )
)
